(kicad_pcb
	(version 20260206)
	(generator "pcbnew")
	(generator_version "10.0")
	(general
		(thickness 1.6)
		(legacy_teardrops no)
	)
	(paper "A4")
	(title_block
		(title "12092022_DA0F0TMDCD0_F0T_Management_Board_D_brd_V3_OCP.brd")
		(comment 1 "Grand Teton / footprints 1314-1319 of 1440")
	)
	(layers
		(0 "F.Cu" signal "TOP")
		(4 "In1.Cu" signal "GND")
		(6 "In2.Cu" signal "IN1")
		(8 "In3.Cu" signal "GND1")
		(10 "In4.Cu" signal "IN2")
		(12 "In5.Cu" signal "VCC")
		(14 "In6.Cu" signal "VCC1")
		(16 "In7.Cu" signal "IN3")
		(18 "In8.Cu" signal "GND2")
		(20 "In9.Cu" signal "IN4")
		(22 "In10.Cu" signal "GND3")
		(2 "B.Cu" signal "BOTTOM")
		(9 "F.Adhes" user "F.Adhesive")
		(11 "B.Adhes" user "B.Adhesive")
		(13 "F.Paste" user "Package Geometry/Pastemask Top")
		(15 "B.Paste" user "Package Geometry/Pastemask Bottom")
		(5 "F.SilkS" user "Ref Des/Silkscreen Top")
		(7 "B.SilkS" user "Ref Des/Silkscreen Bottom")
		(1 "F.Mask" user "Board Geometry/Soldermask Top")
		(3 "B.Mask" user "Board Geometry/Soldermask Bottom")
		(17 "Dwgs.User" user "User.Drawings")
		(19 "Cmts.User" user "User.Comments")
		(21 "Eco1.User" user "User.Eco1")
		(23 "Eco2.User" user "User.Eco2")
		(25 "Edge.Cuts" user "Board Geometry/Outline")
		(27 "Margin" user)
		(31 "F.CrtYd" user "Package Geometry/Place Bound Top")
		(29 "B.CrtYd" user "Package Geometry/Place Bound Bottom")
		(35 "F.Fab" user "Ref Des/Assembly Top")
		(33 "B.Fab" user "Ref Des/Assembly Bottom")
	)
	(footprint ""
		(layer "B.Cu")
		(at 20.4724 -65.1256 90)
		(property "Reference" "R726"
			(at 0 0 90)
			(layer "B.SilkS")
			(hide yes)
			(effects
				(font
					(size 1.27 1.27)
				)
				(justify mirror)
			)
		)
		(property "Value" ""
			(at 0 0 90)
			(layer "B.Fab")
			(effects
				(font
					(size 1.27 1.27)
				)
				(justify mirror)
			)
		)
		(duplicate_pad_numbers_are_jumpers no)
		(fp_line
			(start 0.7874 -0.4064)
			(end -0.7874 -0.4064)
			(stroke
				(width 0.1524)
				(type default)
			)
			(layer "B.SilkS")
		)
		(fp_line
			(start -0.7874 -0.4064)
			(end -0.7874 0.4064)
			(stroke
				(width 0.1524)
				(type default)
			)
			(layer "B.SilkS")
		)
		(fp_line
			(start 0.7874 0.4064)
			(end 0.7874 -0.4064)
			(stroke
				(width 0.1524)
				(type default)
			)
			(layer "B.SilkS")
		)
		(fp_line
			(start -0.7874 0.4064)
			(end 0.7874 0.4064)
			(stroke
				(width 0.1524)
				(type default)
			)
			(layer "B.SilkS")
		)
		(fp_line
			(start 0.67945 -0.305054)
			(end 0.12065 -0.305054)
			(stroke
				(width 0.1)
				(type default)
			)
			(layer "B.Fab")
		)
		(fp_line
			(start 0.12065 -0.305054)
			(end 0.12065 -0.2794)
			(stroke
				(width 0.1)
				(type default)
			)
			(layer "B.Fab")
		)
		(fp_line
			(start -0.12065 -0.3048)
			(end -0.67945 -0.3048)
			(stroke
				(width 0.1)
				(type default)
			)
			(layer "B.Fab")
		)
		(fp_line
			(start -0.67945 -0.3048)
			(end -0.67945 0.3048)
			(stroke
				(width 0.1)
				(type default)
			)
			(layer "B.Fab")
		)
		(fp_line
			(start 0.12065 -0.2794)
			(end -0.12065 -0.2794)
			(stroke
				(width 0.1)
				(type default)
			)
			(layer "B.Fab")
		)
		(fp_line
			(start -0.12065 -0.2794)
			(end -0.12065 -0.3048)
			(stroke
				(width 0.1)
				(type default)
			)
			(layer "B.Fab")
		)
		(fp_line
			(start 0.12065 0.2794)
			(end 0.12065 0.3048)
			(stroke
				(width 0.1)
				(type default)
			)
			(layer "B.Fab")
		)
		(fp_line
			(start -0.120396 0.2794)
			(end 0.12065 0.2794)
			(stroke
				(width 0.1)
				(type default)
			)
			(layer "B.Fab")
		)
		(fp_line
			(start 0.67945 0.3048)
			(end 0.67945 -0.305054)
			(stroke
				(width 0.1)
				(type default)
			)
			(layer "B.Fab")
		)
		(fp_line
			(start 0.12065 0.3048)
			(end 0.67945 0.3048)
			(stroke
				(width 0.1)
				(type default)
			)
			(layer "B.Fab")
		)
		(fp_line
			(start -0.120396 0.3048)
			(end -0.120396 0.2794)
			(stroke
				(width 0.1)
				(type default)
			)
			(layer "B.Fab")
		)
		(fp_line
			(start -0.67945 0.3048)
			(end -0.120396 0.3048)
			(stroke
				(width 0.1)
				(type default)
			)
			(layer "B.Fab")
		)
		(pad "1" smd circle
			(at 0.40005 0 270)
			(size 0 0)
			(layers "B.Cu" "B.Mask" "B.Paste")
			(net "SPA_SIN_SW_BUF_R")
		)
		(pad "2" smd circle
			(at -0.40005 0 270)
			(size 0 0)
			(layers "B.Cu" "B.Mask" "B.Paste")
			(net "SPA_SIN_SW_BUF")
		)
	)
	(footprint ""
		(layer "B.Cu")
		(at 60.663328 -52.136294)
		(property "Reference" "C23"
			(at 0 0 0)
			(layer "B.SilkS")
			(hide yes)
			(effects
				(font
					(size 1.27 1.27)
				)
				(justify mirror)
			)
		)
		(property "Value" ""
			(at 0 0 0)
			(layer "B.Fab")
			(effects
				(font
					(size 1.27 1.27)
				)
				(justify mirror)
			)
		)
		(duplicate_pad_numbers_are_jumpers no)
		(fp_line
			(start -0.7874 -0.4064)
			(end -0.7874 0.4064)
			(stroke
				(width 0.1524)
				(type default)
			)
			(layer "B.SilkS")
		)
		(fp_line
			(start -0.7874 0.4064)
			(end 0.7874 0.4064)
			(stroke
				(width 0.1524)
				(type default)
			)
			(layer "B.SilkS")
		)
		(fp_line
			(start 0.7874 -0.4064)
			(end -0.7874 -0.4064)
			(stroke
				(width 0.1524)
				(type default)
			)
			(layer "B.SilkS")
		)
		(fp_line
			(start 0.7874 0.4064)
			(end 0.7874 -0.4064)
			(stroke
				(width 0.1524)
				(type default)
			)
			(layer "B.SilkS")
		)
		(fp_line
			(start -0.67945 -0.3048)
			(end -0.67945 0.3048)
			(stroke
				(width 0.1)
				(type default)
			)
			(layer "B.Fab")
		)
		(fp_line
			(start -0.67945 0.3048)
			(end -0.120396 0.3048)
			(stroke
				(width 0.1)
				(type default)
			)
			(layer "B.Fab")
		)
		(fp_line
			(start -0.12065 -0.3048)
			(end -0.67945 -0.3048)
			(stroke
				(width 0.1)
				(type default)
			)
			(layer "B.Fab")
		)
		(fp_line
			(start -0.12065 -0.2794)
			(end -0.12065 -0.3048)
			(stroke
				(width 0.1)
				(type default)
			)
			(layer "B.Fab")
		)
		(fp_line
			(start -0.120396 0.2794)
			(end 0.12065 0.2794)
			(stroke
				(width 0.1)
				(type default)
			)
			(layer "B.Fab")
		)
		(fp_line
			(start -0.120396 0.3048)
			(end -0.120396 0.2794)
			(stroke
				(width 0.1)
				(type default)
			)
			(layer "B.Fab")
		)
		(fp_line
			(start 0.12065 -0.305054)
			(end 0.12065 -0.2794)
			(stroke
				(width 0.1)
				(type default)
			)
			(layer "B.Fab")
		)
		(fp_line
			(start 0.12065 -0.2794)
			(end -0.12065 -0.2794)
			(stroke
				(width 0.1)
				(type default)
			)
			(layer "B.Fab")
		)
		(fp_line
			(start 0.12065 0.2794)
			(end 0.12065 0.3048)
			(stroke
				(width 0.1)
				(type default)
			)
			(layer "B.Fab")
		)
		(fp_line
			(start 0.12065 0.3048)
			(end 0.67945 0.3048)
			(stroke
				(width 0.1)
				(type default)
			)
			(layer "B.Fab")
		)
		(fp_line
			(start 0.67945 -0.305054)
			(end 0.12065 -0.305054)
			(stroke
				(width 0.1)
				(type default)
			)
			(layer "B.Fab")
		)
		(fp_line
			(start 0.67945 0.3048)
			(end 0.67945 -0.305054)
			(stroke
				(width 0.1)
				(type default)
			)
			(layer "B.Fab")
		)
		(pad "1" smd circle
			(at 0.40005 0 180)
			(size 0 0)
			(layers "B.Cu" "B.Mask" "B.Paste")
			(net "P0V6_DDR_VREF_AUX")
		)
		(pad "2" smd circle
			(at -0.40005 0 180)
			(size 0 0)
			(layers "B.Cu" "B.Mask" "B.Paste")
			(net "GND")
		)
	)
	(footprint ""
		(layer "B.Cu")
		(at 61.8744 -18.2626)
		(property "Reference" "R274"
			(at 0 0 0)
			(layer "B.SilkS")
			(hide yes)
			(effects
				(font
					(size 1.27 1.27)
				)
				(justify mirror)
			)
		)
		(property "Value" ""
			(at 0 0 0)
			(layer "B.Fab")
			(effects
				(font
					(size 1.27 1.27)
				)
				(justify mirror)
			)
		)
		(duplicate_pad_numbers_are_jumpers no)
		(fp_line
			(start -0.7874 -0.4064)
			(end -0.7874 0.4064)
			(stroke
				(width 0.1524)
				(type default)
			)
			(layer "B.SilkS")
		)
		(fp_line
			(start -0.7874 0.4064)
			(end 0.7874 0.4064)
			(stroke
				(width 0.1524)
				(type default)
			)
			(layer "B.SilkS")
		)
		(fp_line
			(start 0.7874 -0.4064)
			(end -0.7874 -0.4064)
			(stroke
				(width 0.1524)
				(type default)
			)
			(layer "B.SilkS")
		)
		(fp_line
			(start 0.7874 0.4064)
			(end 0.7874 -0.4064)
			(stroke
				(width 0.1524)
				(type default)
			)
			(layer "B.SilkS")
		)
		(fp_line
			(start -0.67945 -0.3048)
			(end -0.67945 0.3048)
			(stroke
				(width 0.1)
				(type default)
			)
			(layer "B.Fab")
		)
		(fp_line
			(start -0.67945 0.3048)
			(end -0.120396 0.3048)
			(stroke
				(width 0.1)
				(type default)
			)
			(layer "B.Fab")
		)
		(fp_line
			(start -0.12065 -0.3048)
			(end -0.67945 -0.3048)
			(stroke
				(width 0.1)
				(type default)
			)
			(layer "B.Fab")
		)
		(fp_line
			(start -0.12065 -0.2794)
			(end -0.12065 -0.3048)
			(stroke
				(width 0.1)
				(type default)
			)
			(layer "B.Fab")
		)
		(fp_line
			(start -0.120396 0.2794)
			(end 0.12065 0.2794)
			(stroke
				(width 0.1)
				(type default)
			)
			(layer "B.Fab")
		)
		(fp_line
			(start -0.120396 0.3048)
			(end -0.120396 0.2794)
			(stroke
				(width 0.1)
				(type default)
			)
			(layer "B.Fab")
		)
		(fp_line
			(start 0.12065 -0.305054)
			(end 0.12065 -0.2794)
			(stroke
				(width 0.1)
				(type default)
			)
			(layer "B.Fab")
		)
		(fp_line
			(start 0.12065 -0.2794)
			(end -0.12065 -0.2794)
			(stroke
				(width 0.1)
				(type default)
			)
			(layer "B.Fab")
		)
		(fp_line
			(start 0.12065 0.2794)
			(end 0.12065 0.3048)
			(stroke
				(width 0.1)
				(type default)
			)
			(layer "B.Fab")
		)
		(fp_line
			(start 0.12065 0.3048)
			(end 0.67945 0.3048)
			(stroke
				(width 0.1)
				(type default)
			)
			(layer "B.Fab")
		)
		(fp_line
			(start 0.67945 -0.305054)
			(end 0.12065 -0.305054)
			(stroke
				(width 0.1)
				(type default)
			)
			(layer "B.Fab")
		)
		(fp_line
			(start 0.67945 0.3048)
			(end 0.67945 -0.305054)
			(stroke
				(width 0.1)
				(type default)
			)
			(layer "B.Fab")
		)
		(pad "1" smd circle
			(at 0.40005 0 180)
			(size 0 0)
			(layers "B.Cu" "B.Mask" "B.Paste")
			(net "P3V3_AUX")
		)
		(pad "2" smd circle
			(at -0.40005 0 180)
			(size 0 0)
			(layers "B.Cu" "B.Mask" "B.Paste")
			(net "DEBUG_PORT_UART_RX")
		)
	)
	(footprint ""
		(layer "B.Cu")
		(at 52.7812 -30.861 -90)
		(property "Reference" "R816"
			(at 0 0 90)
			(layer "B.SilkS")
			(hide yes)
			(effects
				(font
					(size 1.27 1.27)
				)
				(justify mirror)
			)
		)
		(property "Value" ""
			(at 0 0 90)
			(layer "B.Fab")
			(effects
				(font
					(size 1.27 1.27)
				)
				(justify mirror)
			)
		)
		(duplicate_pad_numbers_are_jumpers no)
		(fp_line
			(start -0.7874 0.4064)
			(end 0.7874 0.4064)
			(stroke
				(width 0.1524)
				(type default)
			)
			(layer "B.SilkS")
		)
		(fp_line
			(start 0.7874 0.4064)
			(end 0.7874 -0.4064)
			(stroke
				(width 0.1524)
				(type default)
			)
			(layer "B.SilkS")
		)
		(fp_line
			(start -0.7874 -0.4064)
			(end -0.7874 0.4064)
			(stroke
				(width 0.1524)
				(type default)
			)
			(layer "B.SilkS")
		)
		(fp_line
			(start 0.7874 -0.4064)
			(end -0.7874 -0.4064)
			(stroke
				(width 0.1524)
				(type default)
			)
			(layer "B.SilkS")
		)
		(fp_line
			(start -0.67945 0.3048)
			(end -0.120396 0.3048)
			(stroke
				(width 0.1)
				(type default)
			)
			(layer "B.Fab")
		)
		(fp_line
			(start -0.120396 0.3048)
			(end -0.120396 0.2794)
			(stroke
				(width 0.1)
				(type default)
			)
			(layer "B.Fab")
		)
		(fp_line
			(start 0.12065 0.3048)
			(end 0.67945 0.3048)
			(stroke
				(width 0.1)
				(type default)
			)
			(layer "B.Fab")
		)
		(fp_line
			(start 0.67945 0.3048)
			(end 0.67945 -0.305054)
			(stroke
				(width 0.1)
				(type default)
			)
			(layer "B.Fab")
		)
		(fp_line
			(start -0.120396 0.2794)
			(end 0.12065 0.2794)
			(stroke
				(width 0.1)
				(type default)
			)
			(layer "B.Fab")
		)
		(fp_line
			(start 0.12065 0.2794)
			(end 0.12065 0.3048)
			(stroke
				(width 0.1)
				(type default)
			)
			(layer "B.Fab")
		)
		(fp_line
			(start -0.12065 -0.2794)
			(end -0.12065 -0.3048)
			(stroke
				(width 0.1)
				(type default)
			)
			(layer "B.Fab")
		)
		(fp_line
			(start 0.12065 -0.2794)
			(end -0.12065 -0.2794)
			(stroke
				(width 0.1)
				(type default)
			)
			(layer "B.Fab")
		)
		(fp_line
			(start -0.67945 -0.3048)
			(end -0.67945 0.3048)
			(stroke
				(width 0.1)
				(type default)
			)
			(layer "B.Fab")
		)
		(fp_line
			(start -0.12065 -0.3048)
			(end -0.67945 -0.3048)
			(stroke
				(width 0.1)
				(type default)
			)
			(layer "B.Fab")
		)
		(fp_line
			(start 0.12065 -0.305054)
			(end 0.12065 -0.2794)
			(stroke
				(width 0.1)
				(type default)
			)
			(layer "B.Fab")
		)
		(fp_line
			(start 0.67945 -0.305054)
			(end 0.12065 -0.305054)
			(stroke
				(width 0.1)
				(type default)
			)
			(layer "B.Fab")
		)
		(pad "1" smd circle
			(at 0.40005 0 90)
			(size 0 0)
			(layers "B.Cu" "B.Mask" "B.Paste")
			(net "P3V3_AUX")
		)
		(pad "2" smd circle
			(at -0.40005 0 90)
			(size 0 0)
			(layers "B.Cu" "B.Mask" "B.Paste")
			(net "IRQ_PCH_SCI_WHEA_N")
		)
	)
	(footprint ""
		(layer "B.Cu")
		(at 12.319 -95.504)
		(property "Reference" "R608"
			(at 0 0 0)
			(layer "B.SilkS")
			(hide yes)
			(effects
				(font
					(size 1.27 1.27)
				)
				(justify mirror)
			)
		)
		(property "Value" ""
			(at 0 0 0)
			(layer "B.Fab")
			(effects
				(font
					(size 1.27 1.27)
				)
				(justify mirror)
			)
		)
		(duplicate_pad_numbers_are_jumpers no)
		(fp_line
			(start -0.7874 -0.4064)
			(end -0.7874 0.4064)
			(stroke
				(width 0.1524)
				(type default)
			)
			(layer "B.SilkS")
		)
		(fp_line
			(start -0.7874 0.4064)
			(end 0.7874 0.4064)
			(stroke
				(width 0.1524)
				(type default)
			)
			(layer "B.SilkS")
		)
		(fp_line
			(start 0.7874 -0.4064)
			(end -0.7874 -0.4064)
			(stroke
				(width 0.1524)
				(type default)
			)
			(layer "B.SilkS")
		)
		(fp_line
			(start 0.7874 0.4064)
			(end 0.7874 -0.4064)
			(stroke
				(width 0.1524)
				(type default)
			)
			(layer "B.SilkS")
		)
		(fp_line
			(start -0.67945 -0.3048)
			(end -0.67945 0.3048)
			(stroke
				(width 0.1)
				(type default)
			)
			(layer "B.Fab")
		)
		(fp_line
			(start -0.67945 0.3048)
			(end -0.120396 0.3048)
			(stroke
				(width 0.1)
				(type default)
			)
			(layer "B.Fab")
		)
		(fp_line
			(start -0.12065 -0.3048)
			(end -0.67945 -0.3048)
			(stroke
				(width 0.1)
				(type default)
			)
			(layer "B.Fab")
		)
		(fp_line
			(start -0.12065 -0.2794)
			(end -0.12065 -0.3048)
			(stroke
				(width 0.1)
				(type default)
			)
			(layer "B.Fab")
		)
		(fp_line
			(start -0.120396 0.2794)
			(end 0.12065 0.2794)
			(stroke
				(width 0.1)
				(type default)
			)
			(layer "B.Fab")
		)
		(fp_line
			(start -0.120396 0.3048)
			(end -0.120396 0.2794)
			(stroke
				(width 0.1)
				(type default)
			)
			(layer "B.Fab")
		)
		(fp_line
			(start 0.12065 -0.305054)
			(end 0.12065 -0.2794)
			(stroke
				(width 0.1)
				(type default)
			)
			(layer "B.Fab")
		)
		(fp_line
			(start 0.12065 -0.2794)
			(end -0.12065 -0.2794)
			(stroke
				(width 0.1)
				(type default)
			)
			(layer "B.Fab")
		)
		(fp_line
			(start 0.12065 0.2794)
			(end 0.12065 0.3048)
			(stroke
				(width 0.1)
				(type default)
			)
			(layer "B.Fab")
		)
		(fp_line
			(start 0.12065 0.3048)
			(end 0.67945 0.3048)
			(stroke
				(width 0.1)
				(type default)
			)
			(layer "B.Fab")
		)
		(fp_line
			(start 0.67945 -0.305054)
			(end 0.12065 -0.305054)
			(stroke
				(width 0.1)
				(type default)
			)
			(layer "B.Fab")
		)
		(fp_line
			(start 0.67945 0.3048)
			(end 0.67945 -0.305054)
			(stroke
				(width 0.1)
				(type default)
			)
			(layer "B.Fab")
		)
		(pad "1" smd circle
			(at 0.40005 0 180)
			(size 0 0)
			(layers "B.Cu" "B.Mask" "B.Paste")
			(net "P3V3_AUX")
		)
		(pad "2" smd circle
			(at -0.40005 0 180)
			(size 0 0)
			(layers "B.Cu" "B.Mask" "B.Paste")
			(net "BMC_CPLD_GPIO_13")
		)
	)
	(footprint ""
		(layer "B.Cu")
		(at 55.5752 -64.02324 -90)
		(property "Reference" "R637"
			(at 0 0 90)
			(layer "B.SilkS")
			(hide yes)
			(effects
				(font
					(size 1.27 1.27)
				)
				(justify mirror)
			)
		)
		(property "Value" ""
			(at 0 0 90)
			(layer "B.Fab")
			(effects
				(font
					(size 1.27 1.27)
				)
				(justify mirror)
			)
		)
		(duplicate_pad_numbers_are_jumpers no)
		(fp_line
			(start -0.7874 0.4064)
			(end 0.7874 0.4064)
			(stroke
				(width 0.1524)
				(type default)
			)
			(layer "B.SilkS")
		)
		(fp_line
			(start 0.7874 0.4064)
			(end 0.7874 -0.4064)
			(stroke
				(width 0.1524)
				(type default)
			)
			(layer "B.SilkS")
		)
		(fp_line
			(start -0.7874 -0.4064)
			(end -0.7874 0.4064)
			(stroke
				(width 0.1524)
				(type default)
			)
			(layer "B.SilkS")
		)
		(fp_line
			(start 0.7874 -0.4064)
			(end -0.7874 -0.4064)
			(stroke
				(width 0.1524)
				(type default)
			)
			(layer "B.SilkS")
		)
		(fp_line
			(start -0.67945 0.3048)
			(end -0.120396 0.3048)
			(stroke
				(width 0.1)
				(type default)
			)
			(layer "B.Fab")
		)
		(fp_line
			(start -0.120396 0.3048)
			(end -0.120396 0.2794)
			(stroke
				(width 0.1)
				(type default)
			)
			(layer "B.Fab")
		)
		(fp_line
			(start 0.12065 0.3048)
			(end 0.67945 0.3048)
			(stroke
				(width 0.1)
				(type default)
			)
			(layer "B.Fab")
		)
		(fp_line
			(start 0.67945 0.3048)
			(end 0.67945 -0.305054)
			(stroke
				(width 0.1)
				(type default)
			)
			(layer "B.Fab")
		)
		(fp_line
			(start -0.120396 0.2794)
			(end 0.12065 0.2794)
			(stroke
				(width 0.1)
				(type default)
			)
			(layer "B.Fab")
		)
		(fp_line
			(start 0.12065 0.2794)
			(end 0.12065 0.3048)
			(stroke
				(width 0.1)
				(type default)
			)
			(layer "B.Fab")
		)
		(fp_line
			(start -0.12065 -0.2794)
			(end -0.12065 -0.3048)
			(stroke
				(width 0.1)
				(type default)
			)
			(layer "B.Fab")
		)
		(fp_line
			(start 0.12065 -0.2794)
			(end -0.12065 -0.2794)
			(stroke
				(width 0.1)
				(type default)
			)
			(layer "B.Fab")
		)
		(fp_line
			(start -0.67945 -0.3048)
			(end -0.67945 0.3048)
			(stroke
				(width 0.1)
				(type default)
			)
			(layer "B.Fab")
		)
		(fp_line
			(start -0.12065 -0.3048)
			(end -0.67945 -0.3048)
			(stroke
				(width 0.1)
				(type default)
			)
			(layer "B.Fab")
		)
		(fp_line
			(start 0.12065 -0.305054)
			(end 0.12065 -0.2794)
			(stroke
				(width 0.1)
				(type default)
			)
			(layer "B.Fab")
		)
		(fp_line
			(start 0.67945 -0.305054)
			(end 0.12065 -0.305054)
			(stroke
				(width 0.1)
				(type default)
			)
			(layer "B.Fab")
		)
		(pad "1" smd circle
			(at 0.40005 0 90)
			(size 0 0)
			(layers "B.Cu" "B.Mask" "B.Paste")
			(net "RST_WDTRST_PLD_R1_N")
		)
		(pad "2" smd circle
			(at -0.40005 0 90)
			(size 0 0)
			(layers "B.Cu" "B.Mask" "B.Paste")
			(net "RST_WDTRST_PLD_N")
		)
	)
)
